FILE_TYPE = CONNECTIVITY;
{Allegro Design Entry HDL 17.4-2019 S026 (4007227) 1/17/2022}
"PAGE_NUMBER" = 157;
0"NC";
1"P3V3_AUX\g";
2"GND\g";
3"P3V3_AUX\g";
4"GND\g";
5"P3V3_AUX\g";
6"P3V3_AUX\g";
7"GND\g";
8"GND\g";
9"GND\g";
10"GND\g";
11"GND\g";
12"GND\g";
13"P3V3_AUX\g";
14"P1V2_AUX\g";
15"GND\g";
16"P3V3_AUX\g";
17"P3V3_AUX\g";
18"GND\g";
19"P3V3_AUX\g";
20"XTAL_USB_CPU0_HUB2_XOUT";
21"XTAL_USB_CPU0_HUB2_XIN";
22"GND\g";
23"P1V2_CPU0_USB2_DVDD12\g";
24"GND\g";
25"P3V3_AUX_CPU0_USB2_AVDD33\g";
26"P3V3_AUX_CPU0_USB2_AVDD33\g";
27"P1V2_CPU0_USB2_DVDD12\g";
28"P3V3_AUX_CPU0_USB2_AVDD33\g";
29"USB_HUB2_TI_FULLPWRMGMTZ_MRP_PROG_FUNC3"$PNN"USB_HUB2_TI_FULLPWRMGMTZ_MRP_PR";
30"USB_HUB2_TI_GANGED_MRP_I2C_SLV_CFG0";
31"USB_HUB2_TI_HS_SUSPEND";
32"USB_HUB2_TI_VDD_MRP_USB3DN_TXDM1";
33"SMB_USB_CPU0_HUB1_SDA";
34"SMB_USB_CPU0_HUB1_SCL";
35"USB_HUB2_MRP_CFG_NON_REM";
36"USB_HUB2_TI_VDD_MRP_USB3DN_TXDP3"$PNN"USB_HUB2_TI_VDD_MRP_USB3DN_TXDP";
37"USB_HUB2_TI_VDD_MRP_USB3DN_RXDM1";
38"USB_HUB2_TI_VDD_MRP_USB3DN_TXDP4"$PNN"USB_HUB2_TI_VDD_MRP_USB3DN_TX_1";
39"USB_HUB2_TI_VDD_MRP_USB3DN_RXDP4";
40"USB_HUB2_TI_VDD33_MRP_PROG_FUNC7"$PNN"USB_HUB2_TI_VDD33_MRP_PROG_FUNC";
41"USB_HUB2_MRP_PRT_CTL4_GANGPWR";
42"USB_HUB2_TI_VDD33_MRP_PRT_CTL4_GANGPWR"$PNN"USB_HUB2_TI_VDD33_MRP_PRT_CTL4_";
43"SMB_USB_HUB2_TI_SDA_MRP_PRT_CTL2";
44"SMB_USB_HUB2_TI_SCL_MRP_PRT_CTL1";
45"USB_HUB2_TI_HS_SUSPEND_MRP_CFG_NON_REM";
46"USB_HUB2_TI_GANGED";
47"USB_HUB2_MRP_I2C_SLV_CFG0";
48"USB_HUB2_TI_GANGED_MRP_I2C_SLV_CFG0"$PNN"USB_HUB2_TI_GANGED_MRP_I2C_SLV_";
49"USB_HUB2_TI_SMBUSZ_MRP_PROG_FUNC2"$PNN"USB_HUB2_TI_SMBUSZ_MRP_PROG_FUN";
%"TUSB8042AIRGCR"
"2","(-4400,4500)","0","pure_quanta","I119";
;
LOCATION"U6002"
SEC"2"
ROOM"USB3_HUB2"
VALUE"TUSB8042AIRGCR"
MATERIAL"IC"
PART_TYPE"SMLF"
SEC_TYPE""
CDS_LIB"pure_quanta"
NEEDS_NO_SIZE"TRUE"
CDS_LMAN_SYM_OUTLINE"-575,1425,575,-1425"
PART_NUMBER"AL008042000";
"XI"
$PN"62"21;
"XO"
$PN"61"20;
"VDD_31"
$PN"31"39;
"VDD_21"
$PN"21"36;
"VDD_57"
$PN"57"27;
"VDD_5"
$PN"5"32;
"VDD_8"
$PN"8"37;
"AUTOENZ||HS_SUSPEND"
$PN"45"45;
"VDD_51"
$PN"51"27;
"VDD33_63"
$PN"63"26;
"SMBUSZ||SS_SUSPEND"
$PN"39"49;
"SCL||SMBCLK"
$PN"38"44;
"GANGED||SMBA2||HS_UP"
$PN"42"48;
"FULLPWRMGMTZ||FULLAUTOZ||SMBA1||SS_UP"
$PN"40"29;
"VDD33_52"
$PN"52"26;
"VDD33_34"
$PN"34"42;
"VDD33_16"
$PN"16"40;
"VDD_28"
$PN"28"38;
"SDA||SMBDAT"
$PN"37"43;
"VDD_13"
$PN"13"27;
%"Q_RES"
"1","(-2150,5075)","0","pure_quanta","I122";
;
LOCATION"R6267"
$SEC"1"
CDS_SEC"1"
GROUP"HUB_TI"
TOLERANCE"5%"
PACK_TYPE"0402LF"
MATERIAL"CHIP"
ROOM"USB3_HUB2_TI"
VALUE"0"
CDS_LIB"pure_quanta"
WATTAGE"1/16W"
BOM_COST"VR_SYSTEM "
PART_NUMBER"CS00002JB13";
"B"
$PN"2"27;
"A"
$PN"1"38;
%"Q_RES"
"2","(-525,3375)","0","pure_quanta","I124";
;
LOCATION"R6278"
$SEC"1"
CDS_SEC"1"
GROUP"HUB_MRP"
VALUE"10K"
MATERIAL"EMPTY"
PACK_TYPE"0402LF"
WATTAGE"1/16W"
TOLERANCE"1%"
ROOM"USB3_HUB2_MRP"
CDS_LIB"pure_quanta"
PART_NUMBER"CS31002FB08";
"A"
$PN"1"41;
"B"
$PN"2"2;
%"Q_RES"
"1","(-1800,3650)","0","pure_quanta","I125";
;
LOCATION"R6276"
$SEC"1"
CDS_SEC"1"
GROUP"HUB_MRP"
ROOM"USB3_HUB2_MRP"
MATERIAL"CHIP"
TOLERANCE"5%"
VALUE"0"
PACK_TYPE"0402LF"
BOM_COST"VR_SYSTEM "
WATTAGE"1/16W"
CDS_LIB"pure_quanta"
PART_NUMBER"CS00002JB13";
"B"
$PN"2"41;
"A"
$PN"1"42;
%"UNIVERSAL_POWER"
"1","(-525,4075)","0","pure_quanta_power","I128";
;
HDL_POWER"P3V3_AUX"
CDS_LIB"pure_quanta_power"
BOM_COST"VR_SYSTEM";
"A"1;
%"GND"
"1","(-525,3075)","0","pure_quanta_power","I129";
;
SIZE"1B"
CDS_LIB"pure_quanta_power"
HDL_POWER"GND";
"A<SIZE-1..0>\NAC"2;
%"Q_RES"
"2","(-525,3800)","0","pure_quanta","I130";
;
LOCATION"R6277"
$SEC"1"
CDS_SEC"1"
GROUP"HUB_MRP"
VALUE"10K"
PACK_TYPE"0402LF"
TOLERANCE"1%"
WATTAGE"1/16W"
ROOM"USB3_HUB2_MRP"
MATERIAL"EMPTY"
CDS_LIB"pure_quanta"
PART_NUMBER"CS31002FB08";
"A"
$PN"1"1;
"B"
$PN"2"41;
%"Q_RES"
"1","(-1800,3725)","0","pure_quanta","I131";
;
LOCATION"R6275"
$SEC"1"
CDS_SEC"1"
GROUP"HUB_TI"
MATERIAL"CHIP"
ROOM"USB3_HUB2_TI"
VALUE"0"
PACK_TYPE"0402LF"
TOLERANCE"5%"
BOM_COST"VR_SYSTEM "
WATTAGE"1/16W"
CDS_LIB"pure_quanta"
PART_NUMBER"CS00002JB13";
"B"
$PN"2"28;
"A"
$PN"1"42;
%"UNIVERSAL_POWER"
"1","(-1200,4050)","0","pure_quanta_power","I132";
;
HDL_POWER"P3V3_AUX_CPU0_USB2_AVDD33"
BOM_COST"VR_SYSTEM"
CDS_LIB"pure_quanta_power";
"A"28;
%"UNIVERSAL_POWER"
"1","(-1500,5800)","0","pure_quanta_power","I133";
;
HDL_POWER"P1V2_CPU0_USB2_DVDD12"
BOM_COST"VR_SYSTEM"
CDS_LIB"pure_quanta_power";
"A"27;
%"Q_RES"
"1","(-2125,5525)","0","pure_quanta","I134";
;
LOCATION"R6262"
$SEC"1"
CDS_SEC"1"
GROUP"HUB_TI"
MATERIAL"CHIP"
PACK_TYPE"0402LF"
ROOM"USB3_HUB2_TI"
TOLERANCE"5%"
VALUE"0"
CDS_LIB"pure_quanta"
BOM_COST"VR_SYSTEM "
WATTAGE"1/16W"
PART_NUMBER"CS00002JB13";
"B"
$PN"2"27;
"A"
$PN"1"37;
%"Q_RES"
"1","(-2125,4925)","0","pure_quanta","I136";
;
LOCATION"R6269"
$SEC"1"
CDS_SEC"1"
GROUP"HUB_TI"
PACK_TYPE"0402LF"
MATERIAL"CHIP"
VALUE"0"
TOLERANCE"5%"
ROOM"USB3_HUB2_TI"
WATTAGE"1/16W"
BOM_COST"VR_SYSTEM "
CDS_LIB"pure_quanta"
PART_NUMBER"CS00002JB13";
"B"
$PN"2"27;
"A"
$PN"1"39;
%"UNIVERSAL_POWER"
"1","(-8850,6275)","0","pure_quanta_power","I137";
;
HDL_POWER"P3V3_AUX"
CDS_LIB"pure_quanta_power"
BOM_COST"VR_SYSTEM";
"A"3;
%"Q_RES"
"2","(-8850,5975)","0","pure_quanta","I138";
;
LOCATION"R6282"
$SEC"1"
CDS_SEC"1"
GROUP"HUB_TI"
MATERIAL"EMPTY"
WATTAGE"1/16W"
ROOM"USB3_HUB2_TI"
TOLERANCE"1%"
PACK_TYPE"0402LF"
VALUE"1K"
CDS_LIB"pure_quanta"
PART_NUMBER"CS21002FB06";
"A"
$PN"1"3;
"B"
$PN"2"49;
%"Q_RES"
"2","(-8850,5500)","0","pure_quanta","I139";
;
LOCATION"R6281"
$SEC"1"
CDS_SEC"1"
MATERIAL"EMPTY"
WATTAGE"1/16W"
TOLERANCE"1%"
VALUE"1K"
PACK_TYPE"0402LF"
ROOM"USB3_HUB2_TI"
CDS_LIB"pure_quanta"
PART_NUMBER"CS21002FB06";
"A"
$PN"1"49;
"B"
$PN"2"4;
%"GND"
"1","(-8850,5250)","0","pure_quanta_power","I140";
;
CDS_LIB"pure_quanta_power"
SIZE"1B"
HDL_POWER"GND";
"A<SIZE-1..0>\NAC"4;
%"Q_RES"
"1","(-2150,3875)","0","pure_quanta","I142";
;
LOCATION"R6274"
$SEC"1"
CDS_SEC"1"
GROUP"HUB_TI"
ROOM"USB3_HUB2_TI"
MATERIAL"CHIP"
PACK_TYPE"0402LF"
TOLERANCE"5%"
VALUE"0"
CDS_LIB"pure_quanta"
BOM_COST"VR_SYSTEM "
WATTAGE"1/16W"
PART_NUMBER"CS00002JB13";
"B"
$PN"2"28;
"A"
$PN"1"40;
%"Q_RES"
"1","(-2125,5225)","0","pure_quanta","I145";
;
LOCATION"R6265"
$SEC"1"
CDS_SEC"1"
GROUP"HUB_TI"
PACK_TYPE"0402LF"
MATERIAL"CHIP"
VALUE"0"
ROOM"USB3_HUB2_TI"
TOLERANCE"5%"
CDS_LIB"pure_quanta"
BOM_COST"VR_SYSTEM "
WATTAGE"1/16W"
PART_NUMBER"CS00002JB13";
"B"
$PN"2"27;
"A"
$PN"1"36;
%"Q_RES"
"1","(-6800,5275)","0","pure_quanta","I146";
;
LOCATION"R6280"
$SEC"1"
CDS_SEC"1"
GROUP"HUB_TI"
ROOM"USB3_HUB2_TI"
PACK_TYPE"0402LF"
MATERIAL"CHIP"
TOLERANCE"5%"
VALUE"0"
BOM_COST"VR_SYSTEM "
WATTAGE"1/16W"
CDS_LIB"pure_quanta"
PART_NUMBER"CS00002JB13";
"B"
$PN"2"44;
"A"
$PN"1"34;
%"Q_RES"
"1","(-6775,5475)","0","pure_quanta","I148";
;
LOCATION"R6279"
$SEC"1"
CDS_SEC"1"
GROUP"HUB_TI"
MATERIAL"CHIP"
PACK_TYPE"0402LF"
TOLERANCE"5%"
VALUE"0"
ROOM"USB3_HUB2_TI"
CDS_LIB"pure_quanta"
WATTAGE"1/16W"
BOM_COST"VR_SYSTEM "
PART_NUMBER"CS00002JB13";
"B"
$PN"2"43;
"A"
$PN"1"33;
%"Q_RES"
"1","(-7450,4750)","0","pure_quanta","I150";
;
LOCATION"R6305"
$SEC"1"
CDS_SEC"1"
GROUP"HUB_MRP"
ROOM"USB3_HUB2_MRP"
PACK_TYPE"0402LF"
MATERIAL"CHIP"
TOLERANCE"5%"
VALUE"0"
WATTAGE"1/16W"
BOM_COST"VR_SYSTEM "
CDS_LIB"pure_quanta"
PART_NUMBER"CS00002JB13";
"B"
$PN"2"45;
"A"
$PN"1"35;
%"Q_RES"
"1","(-7450,4925)","0","pure_quanta","I151";
;
LOCATION"R6304"
$SEC"1"
CDS_SEC"1"
GROUP"HUB_TI"
MATERIAL"CHIP"
ROOM"USB3_HUB2_TI"
PACK_TYPE"0402LF"
TOLERANCE"5%"
VALUE"0"
WATTAGE"1/16W"
BOM_COST"VR_SYSTEM "
CDS_LIB"pure_quanta"
PART_NUMBER"CS00002JB13";
"B"
$PN"2"45;
"A"
$PN"1"31;
%"UNIVERSAL_POWER"
"1","(-8700,4800)","0","pure_quanta_power","I152";
;
HDL_POWER"P3V3_AUX"
BOM_COST"VR_SYSTEM"
CDS_LIB"pure_quanta_power";
"A"5;
%"Q_RES"
"2","(-8700,4550)","0","pure_quanta","I153";
;
LOCATION"R6308"
$SEC"1"
CDS_SEC"1"
GROUP"HUB_MRP"
MATERIAL"EMPTY"
WATTAGE"1/16W"
VALUE"200K"
TOLERANCE"1%"
PACK_TYPE"0402LF"
ROOM"USB3_HUB2_MRP"
CDS_LIB"pure_quanta"
PART_NUMBER"CS42002FB05";
"A"
$PN"1"5;
"B"
$PN"2"35;
%"UNIVERSAL_POWER"
"1","(-9125,5350)","0","pure_quanta_power","I154";
;
HDL_POWER"P3V3_AUX"
BOM_COST"VR_SYSTEM"
CDS_LIB"pure_quanta_power";
"A"6;
%"Q_RES"
"2","(-9125,5150)","0","pure_quanta","I155";
;
LOCATION"R6306"
$SEC"1"
CDS_SEC"1"
GROUP"HUB_TI"
ROOM"USB3_HUB2_TI"
TOLERANCE"1%"
MATERIAL"CHIP"
WATTAGE"1/16W"
VALUE"4.7K"
PACK_TYPE"0402LF"
CDS_LIB"pure_quanta"
PART_NUMBER"CS24702FB06";
"A"
$PN"1"6;
"B"
$PN"2"31;
%"Q_RES"
"2","(-9125,4725)","0","pure_quanta","I156";
;
LOCATION"R6307"
$SEC"1"
CDS_SEC"1"
GROUP"HUB_TI"
ROOM"USB3_HUB2_TI"
WATTAGE"1/16W"
VALUE"4.7K"
TOLERANCE"1%"
MATERIAL"EMPTY"
PACK_TYPE"0402LF"
CDS_LIB"pure_quanta"
PART_NUMBER"CS24702FB06";
"A"
$PN"1"31;
"B"
$PN"2"7;
%"GND"
"1","(-9125,4400)","0","pure_quanta_power","I157";
;
SIZE"1B"
CDS_LIB"pure_quanta_power"
HDL_POWER"GND";
"A<SIZE-1..0>\NAC"7;
%"Q_RES"
"2","(-8700,4050)","0","pure_quanta","I158";
;
LOCATION"R6309"
$SEC"1"
CDS_SEC"1"
GROUP"HUB_MRP"
PACK_TYPE"0402LF"
WATTAGE"1/16W"
VALUE"200K"
TOLERANCE"1%"
MATERIAL"CHIP"
ROOM"USB3_HUB2_MRP"
CDS_LIB"pure_quanta"
PART_NUMBER"CS42002FB05";
"A"
$PN"1"35;
"B"
$PN"2"8;
%"GND"
"1","(-8700,3850)","0","pure_quanta_power","I159";
;
SIZE"1B"
CDS_LIB"pure_quanta_power"
HDL_POWER"GND";
"A<SIZE-1..0>\NAC"8;
%"Q_RES"
"1","(-6925,3475)","0","pure_quanta","I160";
;
LOCATION"R6257"
$SEC"1"
CDS_SEC"1"
ROOM"USB3_HUB2"
VALUE"1M"
MATERIAL"CHIP"
TOLERANCE"1%"
WATTAGE"1/16W"
PACK_TYPE"0402LF"
CDS_LIB"pure_quanta"
PART_NUMBER"CS51002FB05";
"B"
$PN"2"21;
"A"
$PN"1"20;
%"GND"
"1","(-6250,2625)","0","pure_quanta_power","I162";
;
CDS_LIB"pure_quanta_power"
SIZE"1B"
HDL_POWER"GND";
"A<SIZE-1..0>\NAC"9;
%"GND"
"1","(-6500,2650)","0","pure_quanta_power","I163";
;
CDS_LIB"pure_quanta_power"
SIZE"1B"
HDL_POWER"GND";
"A<SIZE-1..0>\NAC"10;
%"Q_XTAL_4P_13BI_24GND"
"1","(-6825,3050)","2","pure_quanta","I164";
;
LOCATION"Y6000"
SEC"1"
MATERIAL"MISC"
VALUE"24MHZ"
PART_TYPE"SMLF"
ROOM"USB3_HUB2"
CDS_LIB"pure_quanta"
CDS_LMAN_SYM_OUTLINE"-125,175,125,-175"
PIN_NAMES_ROTATE"True"
SEC_TYPE""
PART_NUMBER"BG624000101";
"X2"
$PN"3"20;
"G2"
$PN"4"12;
"G1"
$PN"2"10;
"X1"
$PN"1"21;
%"GND"
"1","(-7375,2650)","0","pure_quanta_power","I166";
;
SIZE"1B"
CDS_LIB"pure_quanta_power"
HDL_POWER"GND";
"A<SIZE-1..0>\NAC"11;
%"GND"
"1","(-7200,2650)","0","pure_quanta_power","I167";
;
SIZE"1B"
CDS_LIB"pure_quanta_power"
HDL_POWER"GND";
"A<SIZE-1..0>\NAC"12;
%"UNIVERSAL_POWER"
"1","(-2750,3625)","0","pure_quanta_power","I169";
;
HDL_POWER"P3V3_AUX_CPU0_USB2_AVDD33"
BOM_COST"VR_SYSTEM"
CDS_LIB"pure_quanta_power";
"A"26;
%"Q_INDUCTOR"
"1","(-6200,2000)","0","pure_quanta","I17";
;
LOCATION"L6003"
$SEC"1"
CDS_SEC"1"
PACK_TYPE"SMLF"
MATERIAL"IND"
VALUE"BLM21PG221SN1D"
ROOM"USB3_HUB2"
NEEDS_NO_SIZE"TRUE"
CDS_LIB"pure_quanta"
PART_NUMBER"CX1PG221001";
"1"
$PN"1"13;
"2"
$PN"2"25;
%"Q_RES"
"1","(-2150,5675)","0","pure_quanta","I170";
;
LOCATION"R6260"
$SEC"1"
CDS_SEC"1"
GROUP"HUB_TI"
MATERIAL"CHIP"
PACK_TYPE"0402LF"
ROOM"USB3_HUB2_TI"
VALUE"0"
TOLERANCE"5%"
WATTAGE"1/16W"
BOM_COST"VR_SYSTEM "
CDS_LIB"pure_quanta"
PART_NUMBER"CS00002JB13";
"B"
$PN"2"27;
"A"
$PN"1"32;
%"Q_RES"
"2","(-8200,3500)","0","pure_quanta","I171";
;
LOCATION"R6284"
SEC"1"
ROOM"USB3_HUB2_TI"
TOLERANCE"1%"
MATERIAL"CHIP"
PACK_TYPE"0402LF"
WATTAGE"1/16W"
VALUE"10"
CDS_LIB"pure_quanta"
SEC_TYPE"0402LF"
PART_NUMBER"CS01002FB07";
"A"
$PN"1"29;
"B"
$PN"2"15;
%"Q_CAP"
"1","(-7375,2900)","2","pure_quanta","I174";
;
LOCATION"C6090"
SEC"1"
MATERIAL"NPO"
TOLERANCE"5%"
VALUE"27PF"
VOLTAGE"50V"
PACK_TYPE"0402"
ROOM"USB3_HUB2"
SEC_TYPE"0402"
CDS_LIB"pure_quanta"
PART_NUMBER"CH02706JB06";
"B"
$PN"2"11;
"A"
$PN"1"20;
%"Q_CAP"
"1","(-6250,2875)","0","pure_quanta","I175";
;
LOCATION"C6091"
SEC"1"
PACK_TYPE"0402"
VALUE"27PF"
MATERIAL"NPO"
VOLTAGE"50V"
TOLERANCE"5%"
ROOM"USB3_HUB2"
SEC_TYPE"0402"
CDS_LIB"pure_quanta"
PART_NUMBER"CH02706JB06";
"B"
$PN"2"9;
"A"
$PN"1"21;
%"UNIVERSAL_POWER"
"1","(-6650,2225)","0","pure_quanta_power","I18";
;
HDL_POWER"P3V3_AUX"
CDS_LIB"pure_quanta_power"
BOM_COST"VR_SYSTEM";
"A"13;
%"UNIVERSAL_POWER"
"1","(-5425,2225)","0","pure_quanta_power","I19";
;
HDL_POWER"P3V3_AUX_CPU0_USB2_AVDD33"
BOM_COST"VR_SYSTEM"
CDS_LIB"pure_quanta_power";
"A"25;
%"Q_INDUCTOR"
"1","(-7900,1075)","0","pure_quanta","I20";
;
LOCATION"L6004"
$SEC"1"
CDS_SEC"1"
PACK_TYPE"SMLF"
MATERIAL"IND"
VALUE"BLM21PG221SN1D"
ROOM"USB3_HUB2"
CDS_LIB"pure_quanta"
NEEDS_NO_SIZE"TRUE"
PART_NUMBER"CX1PG221001";
"1"
$PN"1"14;
"2"
$PN"2"23;
%"Q_CAP"
"1","(-5425,1675)","0","pure_quanta","I21";
;
LOCATION"C6092"
$SEC"1"
CDS_SEC"1"
VOLTAGE"25V"
ROOM"USB3_HUB2"
TOLERANCE"10%"
VALUE"1UF"
MATERIAL"X6S"
PACK_TYPE"C0402"
CDS_LIB"pure_quanta"
PART_NUMBER"CH5104KEB02";
"B"
$PN"2"24;
"A"
$PN"1"25;
%"Q_CAP"
"1","(-4600,1675)","0","pure_quanta","I22";
;
LOCATION"C6094"
$SEC"1"
CDS_SEC"1"
VALUE"0.01UF"
ROOM"USB3_HUB2"
VOLTAGE"50V"
TOLERANCE"10%"
MATERIAL"X7R"
PACK_TYPE"C0402"
CDS_LIB"pure_quanta"
PART_NUMBER"CH31006KB18";
"B"
$PN"2"24;
"A"
$PN"1"25;
%"Q_CAP"
"1","(-4350,1675)","0","pure_quanta","I23";
;
LOCATION"C6095"
$SEC"1"
CDS_SEC"1"
VALUE"0.1UF"
ROOM"USB3_HUB2"
PACK_TYPE"0402"
MATERIAL"X7R"
VOLTAGE"25V"
TOLERANCE"10%"
CDS_LIB"pure_quanta"
PART_NUMBER"CH4104K1B00";
"B"
$PN"2"24;
"A"
$PN"1"25;
%"Q_CAP"
"1","(-5025,1675)","0","pure_quanta","I24";
;
LOCATION"C6093"
$SEC"1"
CDS_SEC"1"
VOLTAGE"50V"
MATERIAL"COG"
TOLERANCE"0.05P"
VALUE"1PF"
PACK_TYPE"C0402"
ROOM"USB3_HUB2"
CDS_LIB"pure_quanta"
PART_NUMBER"CH-106T0B00";
"B"
$PN"2"24;
"A"
$PN"1"25;
%"Q_CAP"
"1","(-3575,1675)","0","pure_quanta","I25";
;
LOCATION"C6098"
$SEC"1"
CDS_SEC"1"
ROOM"USB3_HUB2"
VOLTAGE"25V"
VALUE"0.1UF"
MATERIAL"X7R"
TOLERANCE"10%"
PACK_TYPE"0402"
CDS_LIB"pure_quanta"
PART_NUMBER"CH4104K1B00";
"B"
$PN"2"24;
"A"
$PN"1"25;
%"Q_CAP"
"1","(-3825,1675)","0","pure_quanta","I26";
;
LOCATION"C6097"
$SEC"1"
CDS_SEC"1"
ROOM"USB3_HUB2"
TOLERANCE"10%"
VOLTAGE"50V"
VALUE"0.01UF"
MATERIAL"X7R"
PACK_TYPE"C0402"
CDS_LIB"pure_quanta"
PART_NUMBER"CH31006KB18";
"B"
$PN"2"24;
"A"
$PN"1"25;
%"Q_CAP"
"1","(-4075,1675)","0","pure_quanta","I27";
;
LOCATION"C6096"
$SEC"1"
CDS_SEC"1"
ROOM"USB3_HUB2"
VALUE"1PF"
TOLERANCE"0.05P"
VOLTAGE"50V"
MATERIAL"COG"
PACK_TYPE"C0402"
CDS_LIB"pure_quanta"
PART_NUMBER"CH-106T0B00";
"B"
$PN"2"24;
"A"
$PN"1"25;
%"Q_CAP"
"1","(-2825,1675)","0","pure_quanta","I28";
;
LOCATION"C6101"
$SEC"1"
CDS_SEC"1"
TOLERANCE"10%"
ROOM"USB3_HUB2"
VOLTAGE"25V"
VALUE"0.1UF"
MATERIAL"X7R"
PACK_TYPE"0402"
CDS_LIB"pure_quanta"
PART_NUMBER"CH4104K1B00";
"B"
$PN"2"24;
"A"
$PN"1"25;
%"Q_CAP"
"1","(-3075,1675)","0","pure_quanta","I29";
;
LOCATION"C6100"
$SEC"1"
CDS_SEC"1"
VALUE"0.01UF"
VOLTAGE"50V"
TOLERANCE"10%"
ROOM"USB3_HUB2"
MATERIAL"X7R"
PACK_TYPE"C0402"
CDS_LIB"pure_quanta"
PART_NUMBER"CH31006KB18";
"B"
$PN"2"24;
"A"
$PN"1"25;
%"Q_CAP"
"1","(-3325,1675)","0","pure_quanta","I30";
;
LOCATION"C6099"
$SEC"1"
CDS_SEC"1"
ROOM"USB3_HUB2"
VALUE"1PF"
VOLTAGE"50V"
MATERIAL"COG"
TOLERANCE"0.05P"
PACK_TYPE"C0402"
CDS_LIB"pure_quanta"
PART_NUMBER"CH-106T0B00";
"B"
$PN"2"24;
"A"
$PN"1"25;
%"Q_CAP"
"1","(-2050,1675)","0","pure_quanta","I31";
;
LOCATION"C6104"
$SEC"1"
CDS_SEC"1"
ROOM"USB3_HUB2"
VOLTAGE"25V"
VALUE"0.1UF"
TOLERANCE"10%"
MATERIAL"X7R"
PACK_TYPE"0402"
CDS_LIB"pure_quanta"
PART_NUMBER"CH4104K1B00";
"B"
$PN"2"24;
"A"
$PN"1"25;
%"Q_CAP"
"1","(-2325,1675)","0","pure_quanta","I32";
;
LOCATION"C6103"
$SEC"1"
CDS_SEC"1"
ROOM"USB3_HUB2"
VALUE"0.01UF"
TOLERANCE"10%"
VOLTAGE"50V"
PACK_TYPE"C0402"
MATERIAL"X7R"
CDS_LIB"pure_quanta"
PART_NUMBER"CH31006KB18";
"B"
$PN"2"24;
"A"
$PN"1"25;
%"Q_CAP"
"1","(-2575,1675)","0","pure_quanta","I33";
;
LOCATION"C6102"
$SEC"1"
CDS_SEC"1"
VOLTAGE"50V"
ROOM"USB3_HUB2"
VALUE"1PF"
TOLERANCE"0.05P"
MATERIAL"COG"
PACK_TYPE"C0402"
CDS_LIB"pure_quanta"
PART_NUMBER"CH-106T0B00";
"B"
$PN"2"24;
"A"
$PN"1"25;
%"GND"
"1","(-5425,1300)","0","pure_quanta_power","I34";
;
SIZE"1B"
CDS_LIB"pure_quanta_power"
HDL_POWER"GND";
"A<SIZE-1..0>\NAC"24;
%"UNIVERSAL_POWER"
"1","(-8300,1275)","0","pure_quanta_power","I35";
;
HDL_POWER"P1V2_AUX"
BOM_COST"VR_SYSTEM"
CDS_LIB"pure_quanta_power";
"A"14;
%"Q_CAP"
"1","(-7100,825)","0","pure_quanta","I36";
;
LOCATION"C6105"
$SEC"1"
CDS_SEC"1"
MATERIAL"X6S"
TOLERANCE"10%"
PACK_TYPE"C0805"
ROOM"USB3_HUB2"
VOLTAGE"25V"
VALUE"10UF"
CDS_LIB"pure_quanta"
PART_NUMBER"CH6104KEA00";
"B"
$PN"2"22;
"A"
$PN"1"23;
%"UNIVERSAL_POWER"
"1","(-7100,1275)","0","pure_quanta_power","I37";
;
HDL_POWER"P1V2_CPU0_USB2_DVDD12"
CDS_LIB"pure_quanta_power"
BOM_COST"VR_SYSTEM";
"A"23;
%"GND"
"1","(-7100,400)","0","pure_quanta_power","I38";
;
CDS_LIB"pure_quanta_power"
SIZE"1B"
HDL_POWER"GND";
"A<SIZE-1..0>\NAC"22;
%"Q_CAP"
"1","(-6025,825)","0","pure_quanta","I39";
;
LOCATION"C6108"
$SEC"1"
CDS_SEC"1"
MATERIAL"X7R"
ROOM"USB3_HUB2"
PACK_TYPE"0402"
VALUE"0.1UF"
VOLTAGE"25V"
TOLERANCE"10%"
CDS_LIB"pure_quanta"
PART_NUMBER"CH4104K1B00";
"B"
$PN"2"22;
"A"
$PN"1"23;
%"Q_CAP"
"1","(-6275,825)","0","pure_quanta","I40";
;
LOCATION"C6107"
$SEC"1"
CDS_SEC"1"
MATERIAL"X7R"
VOLTAGE"50V"
ROOM"USB3_HUB2"
VALUE"0.01UF"
PACK_TYPE"C0402"
TOLERANCE"10%"
CDS_LIB"pure_quanta"
PART_NUMBER"CH31006KB18";
"B"
$PN"2"22;
"A"
$PN"1"23;
%"Q_CAP"
"1","(-6700,825)","0","pure_quanta","I41";
;
LOCATION"C6106"
$SEC"1"
CDS_SEC"1"
MATERIAL"COG"
ROOM"USB3_HUB2"
PACK_TYPE"C0402"
VALUE"1PF"
VOLTAGE"50V"
TOLERANCE"0.05P"
CDS_LIB"pure_quanta"
PART_NUMBER"CH-106T0B00";
"B"
$PN"2"22;
"A"
$PN"1"23;
%"Q_CAP"
"1","(-5175,850)","0","pure_quanta","I42";
;
LOCATION"C6111"
$SEC"1"
CDS_SEC"1"
VALUE"0.1UF"
PACK_TYPE"0402"
MATERIAL"X7R"
TOLERANCE"10%"
ROOM"USB3_HUB2"
VOLTAGE"25V"
CDS_LIB"pure_quanta"
PART_NUMBER"CH4104K1B00";
"B"
$PN"2"22;
"A"
$PN"1"23;
%"Q_CAP"
"1","(-5450,825)","0","pure_quanta","I43";
;
LOCATION"C6110"
$SEC"1"
CDS_SEC"1"
PACK_TYPE"C0402"
ROOM"USB3_HUB2"
TOLERANCE"10%"
MATERIAL"X7R"
VOLTAGE"50V"
VALUE"0.01UF"
CDS_LIB"pure_quanta"
PART_NUMBER"CH31006KB18";
"B"
$PN"2"22;
"A"
$PN"1"23;
%"Q_CAP"
"1","(-5750,850)","0","pure_quanta","I44";
;
LOCATION"C6109"
$SEC"1"
CDS_SEC"1"
MATERIAL"COG"
PACK_TYPE"C0402"
VALUE"1PF"
VOLTAGE"50V"
TOLERANCE"0.05P"
ROOM"USB3_HUB2"
CDS_LIB"pure_quanta"
PART_NUMBER"CH-106T0B00";
"B"
$PN"2"22;
"A"
$PN"1"23;
%"Q_CAP"
"1","(-4250,850)","0","pure_quanta","I45";
;
LOCATION"C6114"
$SEC"1"
CDS_SEC"1"
PACK_TYPE"0402"
ROOM"USB3_HUB2"
VALUE"0.1UF"
VOLTAGE"25V"
MATERIAL"X7R"
TOLERANCE"10%"
CDS_LIB"pure_quanta"
PART_NUMBER"CH4104K1B00";
"B"
$PN"2"22;
"A"
$PN"1"23;
%"Q_CAP"
"1","(-4550,825)","0","pure_quanta","I46";
;
LOCATION"C6113"
$SEC"1"
CDS_SEC"1"
PACK_TYPE"C0402"
MATERIAL"X7R"
TOLERANCE"10%"
ROOM"USB3_HUB2"
VOLTAGE"50V"
VALUE"0.01UF"
CDS_LIB"pure_quanta"
PART_NUMBER"CH31006KB18";
"B"
$PN"2"22;
"A"
$PN"1"23;
%"Q_CAP"
"1","(-4875,850)","0","pure_quanta","I47";
;
LOCATION"C6112"
$SEC"1"
CDS_SEC"1"
MATERIAL"COG"
PACK_TYPE"C0402"
VALUE"1PF"
ROOM"USB3_HUB2"
TOLERANCE"0.05P"
VOLTAGE"50V"
CDS_LIB"pure_quanta"
PART_NUMBER"CH-106T0B00";
"B"
$PN"2"22;
"A"
$PN"1"23;
%"Q_CAP"
"1","(-3400,850)","0","pure_quanta","I48";
;
LOCATION"C6117"
$SEC"1"
CDS_SEC"1"
PACK_TYPE"0402"
ROOM"USB3_HUB2"
TOLERANCE"10%"
MATERIAL"X7R"
VALUE"0.1UF"
VOLTAGE"25V"
CDS_LIB"pure_quanta"
PART_NUMBER"CH4104K1B00";
"B"
$PN"2"22;
"A"
$PN"1"23;
%"Q_CAP"
"1","(-3675,850)","0","pure_quanta","I49";
;
LOCATION"C6116"
$SEC"1"
CDS_SEC"1"
PACK_TYPE"C0402"
VALUE"0.01UF"
TOLERANCE"10%"
MATERIAL"X7R"
VOLTAGE"50V"
ROOM"USB3_HUB2"
CDS_LIB"pure_quanta"
PART_NUMBER"CH31006KB18";
"B"
$PN"2"22;
"A"
$PN"1"23;
%"Q_CAP"
"1","(-3925,850)","0","pure_quanta","I50";
;
LOCATION"C6115"
$SEC"1"
CDS_SEC"1"
PACK_TYPE"C0402"
TOLERANCE"0.05P"
ROOM"USB3_HUB2"
MATERIAL"COG"
VALUE"1PF"
VOLTAGE"50V"
CDS_LIB"pure_quanta"
PART_NUMBER"CH-106T0B00";
"B"
$PN"2"22;
"A"
$PN"1"23;
%"Q_CAP"
"1","(-2200,850)","0","pure_quanta","I51";
;
LOCATION"C6121"
$SEC"1"
CDS_SEC"1"
TOLERANCE"10%"
MATERIAL"X7R"
VOLTAGE"25V"
PACK_TYPE"0402"
VALUE"0.1UF"
ROOM"USB3_HUB2"
CDS_LIB"pure_quanta"
PART_NUMBER"CH4104K1B00";
"B"
$PN"2"22;
"A"
$PN"1"23;
%"Q_CAP"
"1","(-2450,850)","0","pure_quanta","I52";
;
LOCATION"C6120"
$SEC"1"
CDS_SEC"1"
TOLERANCE"10%"
MATERIAL"X7R"
PACK_TYPE"C0402"
VALUE"0.01UF"
VOLTAGE"50V"
ROOM"USB3_HUB2"
CDS_LIB"pure_quanta"
PART_NUMBER"CH31006KB18";
"B"
$PN"2"22;
"A"
$PN"1"23;
%"Q_CAP"
"1","(-2750,850)","0","pure_quanta","I53";
;
LOCATION"C6119"
$SEC"1"
CDS_SEC"1"
PACK_TYPE"C0402"
VALUE"1PF"
MATERIAL"COG"
TOLERANCE"0.05P"
VOLTAGE"50V"
ROOM"USB3_HUB2"
CDS_LIB"pure_quanta"
PART_NUMBER"CH-106T0B00";
"B"
$PN"2"22;
"A"
$PN"1"23;
%"Q_CAP"
"1","(-3125,825)","0","pure_quanta","I54";
;
LOCATION"C6118"
$SEC"1"
CDS_SEC"1"
PACK_TYPE"C0805"
VOLTAGE"25V"
TOLERANCE"10%"
MATERIAL"X6S"
VALUE"10UF"
ROOM"USB3_HUB2"
CDS_LIB"pure_quanta"
PART_NUMBER"CH6104KEA00";
"B"
$PN"2"22;
"A"
$PN"1"23;
%"GND"
"1","(-8200,3250)","0","pure_quanta_power","I61";
;
CDS_LIB"pure_quanta_power"
SIZE"1B"
HDL_POWER"GND";
"A<SIZE-1..0>\NAC"15;
%"Q_RES"
"2","(-8200,3925)","0","pure_quanta","I63";
;
LOCATION"R6283"
$SEC"1"
CDS_SEC"1"
GROUP"HUB_TI"
PACK_TYPE"0402LF"
WATTAGE"1/16W"
ROOM"USB3_HUB2_TI"
TOLERANCE"1%"
VALUE"1K"
MATERIAL"EMPTY"
CDS_LIB"pure_quanta"
PART_NUMBER"CS21002FB06";
"A"
$PN"1"16;
"B"
$PN"2"29;
%"UNIVERSAL_POWER"
"1","(-8200,4175)","0","pure_quanta_power","I64";
;
HDL_POWER"P3V3_AUX"
CDS_LIB"pure_quanta_power"
BOM_COST"VR_SYSTEM";
"A"16;
%"Q_RES"
"1","(-3550,2300)","0","pure_quanta","I75";
;
LOCATION"R6291"
$SEC"1"
CDS_SEC"1"
GROUP"HUB_MRP"
MATERIAL"CHIP"
ROOM"USB3_HUB2_MRP"
TOLERANCE"5%"
PACK_TYPE"0402LF"
VALUE"0"
CDS_LIB"pure_quanta"
WATTAGE"1/16W"
BOM_COST"VR_SYSTEM "
PART_NUMBER"CS00002JB13";
"B"
$PN"2"47;
"A"
$PN"1"30;
%"Q_RES"
"1","(-3575,2725)","0","pure_quanta","I76";
;
LOCATION"R6290"
$SEC"1"
CDS_SEC"1"
GROUP"HUB_TI"
ROOM"USB3_HUB2_TI"
MATERIAL"CHIP"
PACK_TYPE"0402LF"
TOLERANCE"5%"
VALUE"0"
CDS_LIB"pure_quanta"
BOM_COST"VR_SYSTEM "
WATTAGE"1/16W"
PART_NUMBER"CS00002JB13";
"B"
$PN"2"46;
"A"
$PN"1"30;
%"Q_RES"
"2","(-1925,3000)","0","pure_quanta","I77";
;
LOCATION"R6292"
$SEC"1"
CDS_SEC"1"
GROUP"HUB_TI"
ROOM"USB3_HUB2_TI"
PACK_TYPE"0402LF"
VALUE"1K"
MATERIAL"EMPTY"
TOLERANCE"1%"
WATTAGE"1/16W"
CDS_LIB"pure_quanta"
PART_NUMBER"CS21002FB06";
"A"
$PN"1"17;
"B"
$PN"2"46;
%"UNIVERSAL_POWER"
"1","(-1925,3275)","0","pure_quanta_power","I78";
;
HDL_POWER"P3V3_AUX"
BOM_COST"VR_SYSTEM"
CDS_LIB"pure_quanta_power";
"A"17;
%"Q_RES"
"2","(-1925,2525)","0","pure_quanta","I79";
;
LOCATION"R6293"
$SEC"1"
CDS_SEC"1"
GROUP"HUB_TI"
ROOM"USB3_HUB2_TI"
WATTAGE"1/16W"
MATERIAL"CHIP"
PACK_TYPE"0402LF"
VALUE"4.7K"
TOLERANCE"1%"
CDS_LIB"pure_quanta"
PART_NUMBER"CS24702FB06";
"A"
$PN"1"46;
"B"
$PN"2"18;
%"GND"
"1","(-1925,2275)","0","pure_quanta_power","I80";
;
CDS_LIB"pure_quanta_power"
SIZE"1B"
HDL_POWER"GND";
"A<SIZE-1..0>\NAC"18;
%"Q_RES"
"2","(-2400,2425)","0","pure_quanta","I81";
;
LOCATION"R6294"
$SEC"1"
CDS_SEC"1"
GROUP"HUB_MRP"
ROOM"USB3_HUB2_MRP"
WATTAGE"1/16W"
TOLERANCE"1%"
MATERIAL"CHIP"
VALUE"10K"
PACK_TYPE"0402LF"
CDS_LIB"pure_quanta"
PART_NUMBER"CS31002FB08";
"A"
$PN"1"19;
"B"
$PN"2"47;
%"UNIVERSAL_POWER"
"1","(-2400,2625)","0","pure_quanta_power","I82";
;
HDL_POWER"P3V3_AUX"
CDS_LIB"pure_quanta_power"
BOM_COST"VR_SYSTEM";
"A"19;
END.
